(kicad_pcb
	(version 20260206)
	(generator "pcbnew")
	(generator_version "10.0")
	(general
		(thickness 1.6)
		(legacy_teardrops no)
	)
	(paper "A4")
	(title_block
		(title "peb — Lightning_PEB_BRD.brd")
		(comment 1 "Lightning (Wiwynn / Facebook NVMe JBOF) / footprints 456-462 of 2563")
	)
	(layers
		(0 "F.Cu" signal "TOP")
		(4 "In1.Cu" signal "L2GND")
		(6 "In2.Cu" signal "L3")
		(8 "In3.Cu" signal "L4VCC")
		(10 "In4.Cu" signal "L5VCC")
		(12 "In5.Cu" signal "L6")
		(14 "In6.Cu" signal "L7GND")
		(2 "B.Cu" signal "BOTTOM")
		(9 "F.Adhes" user "F.Adhesive")
		(11 "B.Adhes" user "B.Adhesive")
		(13 "F.Paste" user "Package Geometry/Pastemask Top")
		(15 "B.Paste" user "Package Geometry/Pastemask Bottom")
		(5 "F.SilkS" user "Ref Des/Silkscreen Top")
		(7 "B.SilkS" user "Ref Des/Silkscreen Bottom")
		(1 "F.Mask" user "Board Geometry/Soldermask Top")
		(3 "B.Mask" user "Board Geometry/Soldermask Bottom")
		(17 "Dwgs.User" user "User.Drawings")
		(19 "Cmts.User" user "User.Comments")
		(21 "Eco1.User" user "User.Eco1")
		(23 "Eco2.User" user "User.Eco2")
		(25 "Edge.Cuts" user "Board Geometry/Outline")
		(27 "Margin" user)
		(31 "F.CrtYd" user "Package Geometry/Place Bound Top")
		(29 "B.CrtYd" user "Package Geometry/Place Bound Bottom")
		(35 "F.Fab" user "Ref Des/Assembly Top")
		(33 "B.Fab" user "Ref Des/Assembly Bottom")
	)
	(footprint ""
		(layer "F.Cu")
		(at 54.102 -120.269 90)
		(property "Reference" "C188"
			(at 0 0 90)
			(layer "F.SilkS")
			(hide yes)
			(effects
				(font
					(size 1.27 1.27)
				)
			)
		)
		(property "Value" "SC1U10V3KX-4GP-U"
			(at 0 -2.8194 90)
			(unlocked yes)
			(layer "F.Fab")
			(hide yes)
			(effects
				(font
					(size 1.016 1.016)
					(thickness 0.1524)
				)
			)
		)
		(property "Device Type" "C603H36"
			(at 0 -4.3434 90)
			(unlocked yes)
			(layer "F.Fab")
			(hide yes)
			(effects
				(font
					(size 1.016 1.016)
					(thickness 0.1524)
				)
			)
		)
		(duplicate_pad_numbers_are_jumpers no)
		(fp_line
			(start 0.508 0)
			(end -0.508 0)
			(stroke
				(width 0.2032)
				(type default)
			)
			(layer "F.SilkS")
		)
		(fp_rect
			(start -0.5842 1.3335)
			(end 0.5842 -1.3335)
			(stroke
				(width 0)
				(type default)
			)
			(fill no)
			(layer "F.CrtYd")
		)
		(fp_rect
			(start -0.5842 1.3335)
			(end 0.5842 -1.3335)
			(stroke
				(width 0)
				(type default)
			)
			(fill no)
			(layer "F.Fab")
		)
		(pad "1" smd custom
			(at 0 -0.762 90)
			(size 0.2159 0.2159)
			(layers "F.Cu" "F.Mask" "F.Paste")
			(net "JTAG_BMC_TRST_N")
			(options
				(clearance outline)
				(anchor circle)
			)
			(primitives
				(gr_poly
					(pts
						(arc
							(start -0.3302 -0.4318)
							(mid -0.402042 -0.402042)
							(end -0.4318 -0.3302)
						)
						(arc
							(start -0.4318 0.3302)
							(mid -0.402042 0.402042)
							(end -0.3302 0.4318)
						)
						(arc
							(start 0.3302 0.4318)
							(mid 0.402042 0.402042)
							(end 0.4318 0.3302)
						)
						(arc
							(start 0.4318 -0.3302)
							(mid 0.402042 -0.402042)
							(end 0.3302 -0.4318)
						)
					)
					(width 0)
					(fill yes)
				)
			)
		)
		(pad "2" smd custom
			(at 0 0.762 90)
			(size 0.2159 0.2159)
			(layers "F.Cu" "F.Mask" "F.Paste")
			(net "GND")
			(options
				(clearance outline)
				(anchor circle)
			)
			(primitives
				(gr_poly
					(pts
						(arc
							(start -0.3302 -0.4318)
							(mid -0.402042 -0.402042)
							(end -0.4318 -0.3302)
						)
						(arc
							(start -0.4318 0.3302)
							(mid -0.402042 0.402042)
							(end -0.3302 0.4318)
						)
						(arc
							(start 0.3302 0.4318)
							(mid 0.402042 0.402042)
							(end 0.4318 0.3302)
						)
						(arc
							(start 0.4318 -0.3302)
							(mid 0.402042 -0.402042)
							(end 0.3302 -0.4318)
						)
					)
					(width 0)
					(fill yes)
				)
			)
		)
	)
	(footprint ""
		(layer "F.Cu")
		(at 328.324718 -33.433258)
		(property "Reference" "C52"
			(at 0 0 0)
			(layer "F.SilkS")
			(hide yes)
			(effects
				(font
					(size 1.27 1.27)
				)
			)
		)
		(property "Value" "SCD22U10V2KX-1GP"
			(at 1.1811 -2.7051 0)
			(unlocked yes)
			(layer "F.Fab")
			(hide yes)
			(effects
				(font
					(size 1.016 1.016)
					(thickness 0.1524)
				)
			)
		)
		(property "Device Type" "C402H22"
			(at 1.1811 -4.2291 0)
			(unlocked yes)
			(layer "F.Fab")
			(hide yes)
			(effects
				(font
					(size 1.016 1.016)
					(thickness 0.1524)
				)
			)
		)
		(duplicate_pad_numbers_are_jumpers no)
		(fp_rect
			(start -0.4318 0.9525)
			(end 0.4318 -0.9525)
			(stroke
				(width 0)
				(type default)
			)
			(fill no)
			(layer "F.CrtYd")
		)
		(fp_rect
			(start -0.4318 0.9525)
			(end 0.4318 -0.9525)
			(stroke
				(width 0)
				(type default)
			)
			(fill no)
			(layer "F.Fab")
		)
		(pad "1" smd custom
			(at 0 -0.4445)
			(size 0.1524 0.1524)
			(layers "F.Cu" "F.Mask" "F.Paste")
			(net "PCIE_TX_CAP_P15")
			(options
				(clearance outline)
				(anchor circle)
			)
			(primitives
				(gr_poly
					(pts
						(arc
							(start 0.3048 -0.2032)
							(mid 0.275042 -0.275042)
							(end 0.2032 -0.3048)
						)
						(arc
							(start -0.2032 -0.3048)
							(mid -0.275042 -0.275042)
							(end -0.3048 -0.2032)
						)
						(arc
							(start -0.3048 0.2032)
							(mid -0.275042 0.275042)
							(end -0.2032 0.3048)
						)
						(arc
							(start 0.2032 0.3048)
							(mid 0.275042 0.275042)
							(end 0.3048 0.2032)
						)
					)
					(width 0)
					(fill yes)
				)
			)
		)
		(pad "2" smd custom
			(at 0 0.4445)
			(size 0.1524 0.1524)
			(layers "F.Cu" "F.Mask" "F.Paste")
			(net "PCIE_TX_P15")
			(options
				(clearance outline)
				(anchor circle)
			)
			(primitives
				(gr_poly
					(pts
						(arc
							(start 0.3048 -0.2032)
							(mid 0.275042 -0.275042)
							(end 0.2032 -0.3048)
						)
						(arc
							(start -0.2032 -0.3048)
							(mid -0.275042 -0.275042)
							(end -0.3048 -0.2032)
						)
						(arc
							(start -0.3048 0.2032)
							(mid -0.275042 0.275042)
							(end -0.2032 0.3048)
						)
						(arc
							(start 0.2032 0.3048)
							(mid 0.275042 0.275042)
							(end 0.3048 0.2032)
						)
					)
					(width 0)
					(fill yes)
				)
			)
		)
	)
	(footprint ""
		(layer "F.Cu")
		(at 117.309646 -53.591206 -90)
		(property "Reference" "R934"
			(at 0 0 270)
			(layer "F.SilkS")
			(hide yes)
			(effects
				(font
					(size 1.27 1.27)
				)
			)
		)
		(property "Value" "4K7R2F-GP"
			(at 0.064008 -3.993896 270)
			(unlocked yes)
			(layer "F.Fab")
			(hide yes)
			(effects
				(font
					(size 1.016 1.016)
					(thickness 0.1524)
				)
			)
		)
		(property "Device Type" "R402H16"
			(at 0.064008 -5.517896 270)
			(unlocked yes)
			(layer "F.Fab")
			(hide yes)
			(effects
				(font
					(size 1.016 1.016)
					(thickness 0.1524)
				)
			)
		)
		(duplicate_pad_numbers_are_jumpers no)
		(fp_line
			(start -0.508 -0.9398)
			(end -0.508 0.9398)
			(stroke
				(width 0.1524)
				(type default)
			)
			(layer "F.SilkS")
		)
		(fp_line
			(start 0.508 -0.9398)
			(end -0.508 -0.9398)
			(stroke
				(width 0.1524)
				(type default)
			)
			(layer "F.SilkS")
		)
		(fp_rect
			(start -0.508 0.9398)
			(end 0.508 -0.9398)
			(stroke
				(width 0)
				(type default)
			)
			(fill no)
			(layer "F.CrtYd")
		)
		(fp_rect
			(start -0.508 0.9398)
			(end 0.508 -0.9398)
			(stroke
				(width 0)
				(type default)
			)
			(fill no)
			(layer "F.Fab")
		)
		(pad "1" smd custom
			(at 0 -0.4445 270)
			(size 0.1397 0.1397)
			(layers "F.Cu" "F.Mask" "F.Paste")
			(net "BMC_ADD2_GND")
			(options
				(clearance outline)
				(anchor circle)
			)
			(primitives
				(gr_poly
					(pts
						(arc
							(start -0.1778 -0.2794)
							(mid -0.249642 -0.249642)
							(end -0.2794 -0.1778)
						)
						(arc
							(start -0.2794 0.1778)
							(mid -0.249642 0.249642)
							(end -0.1778 0.2794)
						)
						(arc
							(start 0.1778 0.2794)
							(mid 0.249642 0.249642)
							(end 0.2794 0.1778)
						)
						(arc
							(start 0.2794 -0.1778)
							(mid 0.249642 -0.249642)
							(end 0.1778 -0.2794)
						)
					)
					(width 0)
					(fill yes)
				)
			)
		)
		(pad "2" smd custom
			(at 0 0.4445 270)
			(size 0.1397 0.1397)
			(layers "F.Cu" "F.Mask" "F.Paste")
			(net "GND")
			(options
				(clearance outline)
				(anchor circle)
			)
			(primitives
				(gr_poly
					(pts
						(arc
							(start -0.1778 -0.2794)
							(mid -0.249642 -0.249642)
							(end -0.2794 -0.1778)
						)
						(arc
							(start -0.2794 0.1778)
							(mid -0.249642 0.249642)
							(end -0.1778 0.2794)
						)
						(arc
							(start 0.1778 0.2794)
							(mid 0.249642 0.249642)
							(end 0.2794 0.1778)
						)
						(arc
							(start 0.2794 -0.1778)
							(mid 0.249642 -0.249642)
							(end 0.1778 -0.2794)
						)
					)
					(width 0)
					(fill yes)
				)
			)
		)
	)
	(footprint ""
		(layer "F.Cu")
		(at 260.17982 -7.780528 180)
		(property "Reference" "PQ21"
			(at 0 0 180)
			(layer "F.SilkS")
			(hide yes)
			(effects
				(font
					(size 1.27 1.27)
				)
			)
		)
		(property "Value" "AO3400-GP-U"
			(at 0.0254 -12.3444 180)
			(unlocked yes)
			(layer "F.Fab")
			(hide yes)
			(effects
				(font
					(size 1.016 1.016)
					(thickness 0.1524)
				)
			)
		)
		(property "Device Type" "SOT23DGS2D8H50"
			(at 0.0254 -14.2494 180)
			(unlocked yes)
			(layer "F.Fab")
			(hide yes)
			(effects
				(font
					(size 1.016 1.016)
					(thickness 0.1524)
				)
			)
		)
		(duplicate_pad_numbers_are_jumpers no)
		(fp_line
			(start 1.7018 0.254)
			(end -1.7018 0.254)
			(stroke
				(width 0.1524)
				(type default)
			)
			(layer "F.SilkS")
		)
		(fp_line
			(start 1.7018 -0.254)
			(end 1.7018 0.254)
			(stroke
				(width 0.1524)
				(type default)
			)
			(layer "F.SilkS")
		)
		(fp_line
			(start -1.7018 0.254)
			(end -1.7018 -0.254)
			(stroke
				(width 0.1524)
				(type default)
			)
			(layer "F.SilkS")
		)
		(fp_line
			(start -1.7018 -0.254)
			(end 1.7018 -0.254)
			(stroke
				(width 0.1524)
				(type default)
			)
			(layer "F.SilkS")
		)
		(fp_rect
			(start -1.778 1.9812)
			(end 1.778 -1.9812)
			(stroke
				(width 0)
				(type default)
			)
			(fill no)
			(layer "F.CrtYd")
		)
		(fp_poly
			(pts
				(xy -1.778 -1.9812) (xy 1.778 -1.9812) (xy 1.778 1.9812) (xy -1.778 1.9812)
			)
			(stroke
				(width 0)
				(type default)
			)
			(fill no)
			(layer "F.Fab")
		)
		(pad "D" smd custom
			(at 0 -1.1176 180)
			(size 0.254 0.254)
			(layers "F.Cu" "F.Mask" "F.Paste")
			(net "PQ22_G")
			(options
				(clearance outline)
				(anchor circle)
			)
			(primitives
				(gr_poly
					(pts
						(arc
							(start -0.508 -0.4064)
							(mid -0.448484 -0.550084)
							(end -0.3048 -0.6096)
						)
						(arc
							(start 0.3048 -0.6096)
							(mid 0.448484 -0.550084)
							(end 0.508 -0.4064)
						)
						(arc
							(start 0.508 0.4064)
							(mid 0.448484 0.550084)
							(end 0.3048 0.6096)
						)
						(arc
							(start -0.3048 0.6096)
							(mid -0.448484 0.550084)
							(end -0.508 0.4064)
						)
					)
					(width 0)
					(fill yes)
				)
			)
		)
		(pad "G" smd custom
			(at -1.016 1.1176 180)
			(size 0.254 0.254)
			(layers "F.Cu" "F.Mask" "F.Paste")
			(net "PQ21_G")
			(options
				(clearance outline)
				(anchor circle)
			)
			(primitives
				(gr_poly
					(pts
						(arc
							(start -0.508 -0.4064)
							(mid -0.448484 -0.550084)
							(end -0.3048 -0.6096)
						)
						(arc
							(start 0.3048 -0.6096)
							(mid 0.448484 -0.550084)
							(end 0.508 -0.4064)
						)
						(arc
							(start 0.508 0.4064)
							(mid 0.448484 0.550084)
							(end 0.3048 0.6096)
						)
						(arc
							(start -0.3048 0.6096)
							(mid -0.448484 0.550084)
							(end -0.508 0.4064)
						)
					)
					(width 0)
					(fill yes)
				)
			)
		)
		(pad "S" smd custom
			(at 1.016 1.1176 180)
			(size 0.254 0.254)
			(layers "F.Cu" "F.Mask" "F.Paste")
			(net "GND")
			(options
				(clearance outline)
				(anchor circle)
			)
			(primitives
				(gr_poly
					(pts
						(arc
							(start -0.508 -0.4064)
							(mid -0.448484 -0.550084)
							(end -0.3048 -0.6096)
						)
						(arc
							(start 0.3048 -0.6096)
							(mid 0.448484 -0.550084)
							(end 0.508 -0.4064)
						)
						(arc
							(start 0.508 0.4064)
							(mid 0.448484 0.550084)
							(end 0.3048 0.6096)
						)
						(arc
							(start -0.3048 0.6096)
							(mid -0.448484 0.550084)
							(end -0.508 0.4064)
						)
					)
					(width 0)
					(fill yes)
				)
			)
		)
	)
	(footprint ""
		(layer "F.Cu")
		(at 60.2742 -161.8996 180)
		(property "Reference" "PR62"
			(at 0 0 180)
			(layer "F.SilkS")
			(hide yes)
			(effects
				(font
					(size 1.27 1.27)
				)
			)
		)
		(property "Value" "4K42R2F-GP"
			(at 0.064008 -3.993896 180)
			(unlocked yes)
			(layer "F.Fab")
			(hide yes)
			(effects
				(font
					(size 1.016 1.016)
					(thickness 0.1524)
				)
			)
		)
		(property "Device Type" "R402H16"
			(at 0.064008 -5.517896 180)
			(unlocked yes)
			(layer "F.Fab")
			(hide yes)
			(effects
				(font
					(size 1.016 1.016)
					(thickness 0.1524)
				)
			)
		)
		(duplicate_pad_numbers_are_jumpers no)
		(fp_line
			(start 0.508 -0.9398)
			(end -0.508 -0.9398)
			(stroke
				(width 0.1524)
				(type default)
			)
			(layer "F.SilkS")
		)
		(fp_line
			(start -0.508 -0.9398)
			(end -0.508 0.9398)
			(stroke
				(width 0.1524)
				(type default)
			)
			(layer "F.SilkS")
		)
		(fp_rect
			(start -0.508 0.9398)
			(end 0.508 -0.9398)
			(stroke
				(width 0)
				(type default)
			)
			(fill no)
			(layer "F.CrtYd")
		)
		(fp_rect
			(start -0.508 0.9398)
			(end 0.508 -0.9398)
			(stroke
				(width 0)
				(type default)
			)
			(fill no)
			(layer "F.Fab")
		)
		(pad "1" smd custom
			(at 0 -0.4445 180)
			(size 0.1397 0.1397)
			(layers "F.Cu" "F.Mask" "F.Paste")
			(net "P1V53_PWR")
			(options
				(clearance outline)
				(anchor circle)
			)
			(primitives
				(gr_poly
					(pts
						(arc
							(start -0.1778 -0.2794)
							(mid -0.249642 -0.249642)
							(end -0.2794 -0.1778)
						)
						(arc
							(start -0.2794 0.1778)
							(mid -0.249642 0.249642)
							(end -0.1778 0.2794)
						)
						(arc
							(start 0.1778 0.2794)
							(mid 0.249642 0.249642)
							(end 0.2794 0.1778)
						)
						(arc
							(start 0.2794 -0.1778)
							(mid 0.249642 -0.249642)
							(end 0.1778 -0.2794)
						)
					)
					(width 0)
					(fill yes)
				)
			)
		)
		(pad "2" smd custom
			(at 0 0.4445 180)
			(size 0.1397 0.1397)
			(layers "F.Cu" "F.Mask" "F.Paste")
			(net "VR_P1V538_STBY_FB")
			(options
				(clearance outline)
				(anchor circle)
			)
			(primitives
				(gr_poly
					(pts
						(arc
							(start -0.1778 -0.2794)
							(mid -0.249642 -0.249642)
							(end -0.2794 -0.1778)
						)
						(arc
							(start -0.2794 0.1778)
							(mid -0.249642 0.249642)
							(end -0.1778 0.2794)
						)
						(arc
							(start 0.1778 0.2794)
							(mid 0.249642 0.249642)
							(end 0.2794 0.1778)
						)
						(arc
							(start 0.2794 -0.1778)
							(mid 0.249642 -0.249642)
							(end 0.1778 -0.2794)
						)
					)
					(width 0)
					(fill yes)
				)
			)
		)
	)
	(footprint ""
		(layer "F.Cu")
		(at 336.836512 -172.432218)
		(property "Reference" "R7925"
			(at 0 0 0)
			(layer "F.SilkS")
			(hide yes)
			(effects
				(font
					(size 1.27 1.27)
				)
			)
		)
		(property "Value" "0R2J-2-GP"
			(at 0.064008 -3.993896 0)
			(unlocked yes)
			(layer "F.Fab")
			(hide yes)
			(effects
				(font
					(size 1.016 1.016)
					(thickness 0.1524)
				)
			)
		)
		(property "Device Type" "R402H16"
			(at 0.064008 -5.517896 0)
			(unlocked yes)
			(layer "F.Fab")
			(hide yes)
			(effects
				(font
					(size 1.016 1.016)
					(thickness 0.1524)
				)
			)
		)
		(duplicate_pad_numbers_are_jumpers no)
		(fp_line
			(start -0.508 -0.9398)
			(end -0.508 0.9398)
			(stroke
				(width 0.1524)
				(type default)
			)
			(layer "F.SilkS")
		)
		(fp_line
			(start 0.508 -0.9398)
			(end -0.508 -0.9398)
			(stroke
				(width 0.1524)
				(type default)
			)
			(layer "F.SilkS")
		)
		(fp_rect
			(start -0.508 0.9398)
			(end 0.508 -0.9398)
			(stroke
				(width 0)
				(type default)
			)
			(fill no)
			(layer "F.CrtYd")
		)
		(fp_rect
			(start -0.508 0.9398)
			(end 0.508 -0.9398)
			(stroke
				(width 0)
				(type default)
			)
			(fill no)
			(layer "F.Fab")
		)
		(pad "1" smd custom
			(at 0 -0.4445)
			(size 0.1397 0.1397)
			(layers "F.Cu" "F.Mask" "F.Paste")
			(net "SSD_PRSNT#9")
			(options
				(clearance outline)
				(anchor circle)
			)
			(primitives
				(gr_poly
					(pts
						(arc
							(start -0.1778 -0.2794)
							(mid -0.249642 -0.249642)
							(end -0.2794 -0.1778)
						)
						(arc
							(start -0.2794 0.1778)
							(mid -0.249642 0.249642)
							(end -0.1778 0.2794)
						)
						(arc
							(start 0.1778 0.2794)
							(mid 0.249642 0.249642)
							(end 0.2794 0.1778)
						)
						(arc
							(start 0.2794 -0.1778)
							(mid 0.249642 -0.249642)
							(end 0.1778 -0.2794)
						)
					)
					(width 0)
					(fill yes)
				)
			)
		)
		(pad "2" smd custom
			(at 0 0.4445)
			(size 0.1397 0.1397)
			(layers "F.Cu" "F.Mask" "F.Paste")
			(net "SSD_PRSNT#9_R")
			(options
				(clearance outline)
				(anchor circle)
			)
			(primitives
				(gr_poly
					(pts
						(arc
							(start -0.1778 -0.2794)
							(mid -0.249642 -0.249642)
							(end -0.2794 -0.1778)
						)
						(arc
							(start -0.2794 0.1778)
							(mid -0.249642 0.249642)
							(end -0.1778 0.2794)
						)
						(arc
							(start 0.1778 0.2794)
							(mid 0.249642 0.249642)
							(end 0.2794 0.1778)
						)
						(arc
							(start 0.2794 -0.1778)
							(mid 0.249642 -0.249642)
							(end 0.1778 -0.2794)
						)
					)
					(width 0)
					(fill yes)
				)
			)
		)
	)
	(footprint ""
		(layer "F.Cu")
		(at 346.456 -55.118 90)
		(property "Reference" "PC219"
			(at 0 0 90)
			(layer "F.SilkS")
			(hide yes)
			(effects
				(font
					(size 1.27 1.27)
				)
			)
		)
		(property "Value" "SC22U25V6KX-GP-U"
			(at -2.860802 -5.279644 90)
			(unlocked yes)
			(layer "F.Fab")
			(hide yes)
			(effects
				(font
					(size 1.016 1.016)
					(thickness 0.1524)
				)
			)
		)
		(property "Device Type" "C1206-TO0D3H75"
			(at -2.860802 -6.803644 90)
			(unlocked yes)
			(layer "F.Fab")
			(hide yes)
			(effects
				(font
					(size 1.016 1.016)
					(thickness 0.1524)
				)
			)
		)
		(duplicate_pad_numbers_are_jumpers no)
		(fp_line
			(start 1.3081 -2.3749)
			(end 1.3081 2.3749)
			(stroke
				(width 0.1524)
				(type default)
			)
			(layer "F.SilkS")
		)
		(fp_line
			(start -1.3081 -2.3749)
			(end 1.3081 -2.3749)
			(stroke
				(width 0.1524)
				(type default)
			)
			(layer "F.SilkS")
		)
		(fp_line
			(start 1.3081 2.3749)
			(end -1.3081 2.3749)
			(stroke
				(width 0.1524)
				(type default)
			)
			(layer "F.SilkS")
		)
		(fp_line
			(start -1.3081 2.3749)
			(end -1.3081 -2.3749)
			(stroke
				(width 0.1524)
				(type default)
			)
			(layer "F.SilkS")
		)
		(fp_rect
			(start -0.8001 1.6002)
			(end 0.8001 -1.6002)
			(stroke
				(width 0)
				(type default)
			)
			(fill no)
			(layer "F.CrtYd")
		)
		(fp_poly
			(pts
				(xy -1.5621 2.4511) (xy -1.5621 1.6002) (xy 0.8001 1.6002) (xy 0.8001 -1.6002) (xy -0.8001 -1.6002)
				(xy -0.8001 1.5875) (xy -1.5621 1.5875) (xy -1.5621 -2.4511) (xy 1.5621 -2.4511) (xy 1.5621 2.4511)
			)
			(stroke
				(width 0)
				(type default)
			)
			(fill no)
			(layer "F.CrtYd")
		)
		(fp_rect
			(start -1.5621 2.4511)
			(end 1.5621 -2.4511)
			(stroke
				(width 0)
				(type default)
			)
			(fill no)
			(layer "F.Fab")
		)
		(pad "1" smd rect
			(at 0 -1.392936 90)
			(size 2.1082 1.4478)
			(layers "F.Cu" "F.Mask" "F.Paste")
			(net "P0V9_E_VIN")
		)
		(pad "2" smd rect
			(at 0 1.392936 90)
			(size 2.1082 1.4478)
			(layers "F.Cu" "F.Mask" "F.Paste")
			(net "GND")
		)
	)
)
